(kicad_pcb
	(version 20241229)
	(generator "pcbnew")
	(generator_version "9.0")
	(general
		(thickness 1.6642)
		(legacy_teardrops no)
	)
	(paper "A3")
	(title_block
		(title "PolarFire SoM")
		(date "2025-07-22")
		(rev "1.1.4")
		(company "Antmicro Ltd")
		(comment 1 "www.antmicro.com")
		(comment 9 "footprints 18-18 of 470")
	)
	(layers
		(0 "F.Cu" mixed)
		(4 "In1.Cu" power)
		(6 "In2.Cu" signal)
		(8 "In3.Cu" power)
		(10 "In4.Cu" signal)
		(12 "In5.Cu" power)
		(14 "In6.Cu" power)
		(16 "In7.Cu" signal)
		(18 "In8.Cu" power)
		(20 "In9.Cu" signal)
		(22 "In10.Cu" power)
		(24 "In11.Cu" signal)
		(26 "In12.Cu" signal)
		(2 "B.Cu" mixed)
		(9 "F.Adhes" user "F.Adhesive")
		(11 "B.Adhes" user "B.Adhesive")
		(13 "F.Paste" user)
		(15 "B.Paste" user)
		(5 "F.SilkS" user "F.Silkscreen")
		(7 "B.SilkS" user "B.Silkscreen")
		(1 "F.Mask" user)
		(3 "B.Mask" user)
		(17 "Dwgs.User" user "User.Drawings")
		(19 "Cmts.User" user "User.Comments")
		(21 "Eco1.User" user "User.Eco1")
		(23 "Eco2.User" user "User.Eco2")
		(25 "Edge.Cuts" user)
		(27 "Margin" user)
		(31 "F.CrtYd" user "F.Courtyard")
		(29 "B.CrtYd" user "B.Courtyard")
		(35 "F.Fab" user)
		(33 "B.Fab" user)
	)
	(footprint "antmicro-footprints:MP_NPTH_Drill2.7mm"
		(locked yes)
		(layer "F.Cu")
		(at 226.017 119.336)
		(property "Reference" "MP4"
			(at 0 -1.8 0)
			(layer "F.SilkS")
			(hide yes)
			(effects
				(font
					(size 0.7 0.7)
					(thickness 0.15)
				)
				(justify left bottom)
			)
		)
		(property "Value" "MP_NPTH_Drill2.7mm"
			(at 0 2.3 0)
			(layer "F.Fab")
			(hide yes)
			(effects
				(font
					(size 0.7 0.7)
					(thickness 0.15)
				)
				(justify left bottom)
			)
		)
		(property "Description" "Mechanical part"
			(at 0 0 0)
			(layer "F.Fab")
			(hide yes)
			(effects
				(font
					(size 1.27 1.27)
					(thickness 0.15)
				)
			)
		)
		(property "Author" "Antmicro"
			(at 0 0 0)
			(layer "F.Fab")
			(hide yes)
			(effects
				(font
					(size 1 1)
					(thickness 0.15)
				)
			)
		)
		(property "License" "Apache-2.0"
			(at 0 0 0)
			(layer "F.Fab")
			(hide yes)
			(effects
				(font
					(size 1 1)
					(thickness 0.15)
				)
			)
		)
		(property "exclude_from_bom" ""
			(at 0 0 0)
			(layer "F.Fab")
			(hide yes)
			(effects
				(font
					(size 1 1)
					(thickness 0.15)
				)
			)
		)
		(sheetfile "polarfire-som.kicad_sch")
		(attr board_only exclude_from_pos_files exclude_from_bom)
		(fp_circle
			(center 0 0)
			(end 1.45 0)
			(stroke
				(width 0.05)
				(type default)
			)
			(fill no)
			(layer "F.CrtYd")
		)
		(fp_text user "Author: Antmicro"
			(at 0 5.95 0)
			(layer "F.Fab")
			(effects
				(font
					(size 0.7 0.7)
					(thickness 0.15)
				)
				(justify left bottom)
			)
		)
		(fp_text user "${REFERENCE}"
			(at 0 4.749 0)
			(layer "F.Fab")
			(effects
				(font
					(size 0.7 0.7)
					(thickness 0.15)
				)
				(justify left bottom)
			)
		)
		(fp_text user "License: Apache-2.0"
			(at 0 7.15 0)
			(layer "F.Fab")
			(effects
				(font
					(size 0.7 0.7)
					(thickness 0.15)
				)
				(justify left bottom)
			)
		)
		(pad "" np_thru_hole circle
			(at 0 0)
			(size 2.7 2.7)
			(drill 2.7)
			(layers "F&B.Cu" "*.Mask")
		)
	)
)
